# S9S_MB_2U (Grand Teton) — schematic netlist excerpt (pin names and nets, part order shuffled) for the footprints in the layout excerpt that follows; sources: Cadence DE-HDL packaged netlist, KiCad conversion of 03242023_DA0F0TMBIJ0_F0T_Motherboard_J_brd_V01_OCP.brd

PR1780  Q_RES  3.3 1% CHIP  pkg 0402LF  page 271 : A = SW_PVCCFA_EHV_FIVRA_CPU0_BOOT1 ; B = SW_PVCCFA_EHV_FIVRA_CPU0_BOOT1_
R3063  Q_RES  33.2 1% CHIP  pkg 0402LF  page 151 : A = FM_PDB_BUF_EN_R ; B = FM_UART_EN

(kicad_pcb
	(version 20260206)
	(generator "pcbnew")
	(generator_version "10.0")
	(general
		(thickness 1.6)
		(legacy_teardrops no)
	)
	(paper "A4")
	(title_block
		(title "03242023_DA0F0TMBIJ0_F0T_Motherboard_J_brd_V01_OCP.brd")
		(comment 1 "Grand Teton / footprints 2191-2192 of 6105")
	)
	(layers
		(0 "F.Cu" signal "TOP")
		(4 "In1.Cu" signal "GND")
		(6 "In2.Cu" signal "IN1")
		(8 "In3.Cu" signal "GND1")
		(10 "In4.Cu" signal "IN2")
		(12 "In5.Cu" signal "GND2")
		(14 "In6.Cu" signal "IN3")
		(16 "In7.Cu" signal "GND3")
		(18 "In8.Cu" signal "VCC")
		(20 "In9.Cu" signal "VCC1")
		(22 "In10.Cu" signal "GND4")
		(24 "In11.Cu" signal "IN4")
		(26 "In12.Cu" signal "GND5")
		(28 "In13.Cu" signal "IN5")
		(30 "In14.Cu" signal "GND6")
		(32 "In15.Cu" signal "IN6")
		(34 "In16.Cu" signal "GND7")
		(2 "B.Cu" signal "BOTTOM")
		(9 "F.Adhes" user "F.Adhesive")
		(11 "B.Adhes" user "B.Adhesive")
		(13 "F.Paste" user "Package Geometry/Pastemask Top")
		(15 "B.Paste" user "Package Geometry/Pastemask Bottom")
		(5 "F.SilkS" user "Ref Des/Silkscreen Top")
		(7 "B.SilkS" user "Ref Des/Silkscreen Bottom")
		(1 "F.Mask" user "Board Geometry/Soldermask Top")
		(3 "B.Mask" user "Board Geometry/Soldermask Bottom")
		(17 "Dwgs.User" user "User.Drawings")
		(19 "Cmts.User" user "User.Comments")
		(21 "Eco1.User" user "User.Eco1")
		(23 "Eco2.User" user "User.Eco2")
		(25 "Edge.Cuts" user "Board Geometry/Outline")
		(27 "Margin" user)
		(31 "F.CrtYd" user "Package Geometry/Place Bound Top")
		(29 "B.CrtYd" user "Package Geometry/Place Bound Bottom")
		(35 "F.Fab" user "Ref Des/Assembly Top")
		(33 "B.Fab" user "Ref Des/Assembly Bottom")
	)
	(footprint ""
		(layer "F.Cu")
		(at 361.36072 -402.9456 90)
		(property "Reference" "R3063"
			(at 0 0 90)
			(layer "F.SilkS")
			(hide yes)
			(effects
				(font
					(size 1.27 1.27)
				)
			)
		)
		(property "Value" ""
			(at 0 0 90)
			(layer "F.Fab")
			(effects
				(font
					(size 1.27 1.27)
				)
			)
		)
		(duplicate_pad_numbers_are_jumpers no)
		(fp_line
			(start 0.7874 -0.4064)
			(end 0.7874 0.4064)
			(stroke
				(width 0.1524)
				(type default)
			)
			(layer "F.SilkS")
		)
		(fp_line
			(start -0.7874 -0.4064)
			(end 0.7874 -0.4064)
			(stroke
				(width 0.1524)
				(type default)
			)
			(layer "F.SilkS")
		)
		(fp_line
			(start 0.7874 0.4064)
			(end -0.7874 0.4064)
			(stroke
				(width 0.1524)
				(type default)
			)
			(layer "F.SilkS")
		)
		(fp_line
			(start -0.7874 0.4064)
			(end -0.7874 -0.4064)
			(stroke
				(width 0.1524)
				(type default)
			)
			(layer "F.SilkS")
		)
		(fp_line
			(start -0.12065 -0.305054)
			(end -0.12065 -0.2794)
			(stroke
				(width 0.1)
				(type default)
			)
			(layer "F.Fab")
		)
		(fp_line
			(start -0.67945 -0.305054)
			(end -0.12065 -0.305054)
			(stroke
				(width 0.1)
				(type default)
			)
			(layer "F.Fab")
		)
		(fp_line
			(start 0.67945 -0.3048)
			(end 0.67945 0.3048)
			(stroke
				(width 0.1)
				(type default)
			)
			(layer "F.Fab")
		)
		(fp_line
			(start 0.12065 -0.3048)
			(end 0.67945 -0.3048)
			(stroke
				(width 0.1)
				(type default)
			)
			(layer "F.Fab")
		)
		(fp_line
			(start 0.12065 -0.2794)
			(end 0.12065 -0.3048)
			(stroke
				(width 0.1)
				(type default)
			)
			(layer "F.Fab")
		)
		(fp_line
			(start -0.12065 -0.2794)
			(end 0.12065 -0.2794)
			(stroke
				(width 0.1)
				(type default)
			)
			(layer "F.Fab")
		)
		(fp_line
			(start 0.120396 0.2794)
			(end -0.12065 0.2794)
			(stroke
				(width 0.1)
				(type default)
			)
			(layer "F.Fab")
		)
		(fp_line
			(start -0.12065 0.2794)
			(end -0.12065 0.3048)
			(stroke
				(width 0.1)
				(type default)
			)
			(layer "F.Fab")
		)
		(fp_line
			(start 0.67945 0.3048)
			(end 0.120396 0.3048)
			(stroke
				(width 0.1)
				(type default)
			)
			(layer "F.Fab")
		)
		(fp_line
			(start 0.120396 0.3048)
			(end 0.120396 0.2794)
			(stroke
				(width 0.1)
				(type default)
			)
			(layer "F.Fab")
		)
		(fp_line
			(start -0.12065 0.3048)
			(end -0.67945 0.3048)
			(stroke
				(width 0.1)
				(type default)
			)
			(layer "F.Fab")
		)
		(fp_line
			(start -0.67945 0.3048)
			(end -0.67945 -0.305054)
			(stroke
				(width 0.1)
				(type default)
			)
			(layer "F.Fab")
		)
		(pad "1" smd circle
			(at -0.40005 0 90)
			(size 0 0)
			(layers "F.Cu" "F.Mask" "F.Paste")
			(net "FM_PDB_BUF_EN_R")
		)
		(pad "2" smd circle
			(at 0.40005 0 90)
			(size 0 0)
			(layers "F.Cu" "F.Mask" "F.Paste")
			(net "FM_UART_EN")
		)
	)
	(footprint ""
		(layer "F.Cu")
		(at 416.919664 -366.691164 90)
		(property "Reference" "PR1780"
			(at 0 0 90)
			(layer "F.SilkS")
			(hide yes)
			(effects
				(font
					(size 1.27 1.27)
				)
			)
		)
		(property "Value" ""
			(at 0 0 90)
			(layer "F.Fab")
			(effects
				(font
					(size 1.27 1.27)
				)
			)
		)
		(duplicate_pad_numbers_are_jumpers no)
		(fp_line
			(start 0.7874 -0.4064)
			(end 0.7874 0.4064)
			(stroke
				(width 0.1524)
				(type default)
			)
			(layer "F.SilkS")
		)
		(fp_line
			(start -0.7874 -0.4064)
			(end 0.7874 -0.4064)
			(stroke
				(width 0.1524)
				(type default)
			)
			(layer "F.SilkS")
		)
		(fp_line
			(start 0.7874 0.4064)
			(end -0.7874 0.4064)
			(stroke
				(width 0.1524)
				(type default)
			)
			(layer "F.SilkS")
		)
		(fp_line
			(start -0.7874 0.4064)
			(end -0.7874 -0.4064)
			(stroke
				(width 0.1524)
				(type default)
			)
			(layer "F.SilkS")
		)
		(fp_line
			(start -0.12065 -0.305054)
			(end -0.12065 -0.2794)
			(stroke
				(width 0.1)
				(type default)
			)
			(layer "F.Fab")
		)
		(fp_line
			(start -0.67945 -0.305054)
			(end -0.12065 -0.305054)
			(stroke
				(width 0.1)
				(type default)
			)
			(layer "F.Fab")
		)
		(fp_line
			(start 0.67945 -0.3048)
			(end 0.67945 0.3048)
			(stroke
				(width 0.1)
				(type default)
			)
			(layer "F.Fab")
		)
		(fp_line
			(start 0.12065 -0.3048)
			(end 0.67945 -0.3048)
			(stroke
				(width 0.1)
				(type default)
			)
			(layer "F.Fab")
		)
		(fp_line
			(start 0.12065 -0.2794)
			(end 0.12065 -0.3048)
			(stroke
				(width 0.1)
				(type default)
			)
			(layer "F.Fab")
		)
		(fp_line
			(start -0.12065 -0.2794)
			(end 0.12065 -0.2794)
			(stroke
				(width 0.1)
				(type default)
			)
			(layer "F.Fab")
		)
		(fp_line
			(start 0.120396 0.2794)
			(end -0.12065 0.2794)
			(stroke
				(width 0.1)
				(type default)
			)
			(layer "F.Fab")
		)
		(fp_line
			(start -0.12065 0.2794)
			(end -0.12065 0.3048)
			(stroke
				(width 0.1)
				(type default)
			)
			(layer "F.Fab")
		)
		(fp_line
			(start 0.67945 0.3048)
			(end 0.120396 0.3048)
			(stroke
				(width 0.1)
				(type default)
			)
			(layer "F.Fab")
		)
		(fp_line
			(start 0.120396 0.3048)
			(end 0.120396 0.2794)
			(stroke
				(width 0.1)
				(type default)
			)
			(layer "F.Fab")
		)
		(fp_line
			(start -0.12065 0.3048)
			(end -0.67945 0.3048)
			(stroke
				(width 0.1)
				(type default)
			)
			(layer "F.Fab")
		)
		(fp_line
			(start -0.67945 0.3048)
			(end -0.67945 -0.305054)
			(stroke
				(width 0.1)
				(type default)
			)
			(layer "F.Fab")
		)
		(pad "1" smd circle
			(at -0.40005 0 90)
			(size 0 0)
			(layers "F.Cu" "F.Mask" "F.Paste")
			(net "SW_PVCCFA_EHV_FIVRA_CPU0_BOOT1")
		)
		(pad "2" smd circle
			(at 0.40005 0 90)
			(size 0 0)
			(layers "F.Cu" "F.Mask" "F.Paste")
			(net "SW_PVCCFA_EHV_FIVRA_CPU0_BOOT1_")
		)
	)
)
